(kicad_pcb
	(version 20260206)
	(generator "pcbnew")
	(generator_version "10.0")
	(general
		(thickness 1.6)
		(legacy_teardrops no)
	)
	(paper "A4")
	(title_block
		(title "Wiwynn_Tioga_Pass_MB.brd")
		(comment 1 "Tioga Pass / footprints 3900-3906 of 4770")
	)
	(layers
		(0 "F.Cu" signal "TOP")
		(4 "In1.Cu" signal "L2GND")
		(6 "In2.Cu" signal "L3")
		(8 "In3.Cu" signal "L4GND")
		(10 "In4.Cu" signal "L5")
		(12 "In5.Cu" signal "L6GND")
		(14 "In6.Cu" signal "L7VCC")
		(16 "In7.Cu" signal "L8VCC")
		(18 "In8.Cu" signal "L9GND")
		(20 "In9.Cu" signal "L10")
		(22 "In10.Cu" signal "L11GND")
		(24 "In11.Cu" signal "L12")
		(26 "In12.Cu" signal "L13GND")
		(2 "B.Cu" signal "BOTTOM")
		(9 "F.Adhes" user "F.Adhesive")
		(11 "B.Adhes" user "B.Adhesive")
		(13 "F.Paste" user "Package Geometry/Pastemask Top")
		(15 "B.Paste" user "Package Geometry/Pastemask Bottom")
		(5 "F.SilkS" user "Ref Des/Silkscreen Top")
		(7 "B.SilkS" user "Ref Des/Silkscreen Bottom")
		(1 "F.Mask" user "Board Geometry/Soldermask Top")
		(3 "B.Mask" user "Board Geometry/Soldermask Bottom")
		(17 "Dwgs.User" user "User.Drawings")
		(19 "Cmts.User" user "User.Comments")
		(21 "Eco1.User" user "User.Eco1")
		(23 "Eco2.User" user "User.Eco2")
		(25 "Edge.Cuts" user "Board Geometry/Outline")
		(27 "Margin" user)
		(31 "F.CrtYd" user "Package Geometry/Place Bound Top")
		(29 "B.CrtYd" user "Package Geometry/Place Bound Bottom")
		(35 "F.Fab" user "Ref Des/Assembly Top")
		(33 "B.Fab" user "Ref Des/Assembly Bottom")
	)
	(footprint ""
		(layer "B.Cu")
		(at 393.375896 -51.66868 90)
		(property "Reference" "U3T1"
			(at 0 0 90)
			(layer "B.SilkS")
			(hide yes)
			(effects
				(font
					(size 1.27 1.27)
				)
				(justify mirror)
			)
		)
		(property "Value" "*"
			(at 6.7945 -2.3241 90)
			(unlocked yes)
			(layer "B.Fab")
			(hide yes)
			(effects
				(font
					(size 1.27 1.016)
					(thickness 0.1524)
				)
				(justify mirror)
			)
		)
		(property "Device Type" "W25Q256FVFIG-GP_MEMORY-G4-W25QA"
			(at 6.7945 -3.8481 90)
			(unlocked yes)
			(layer "B.Fab")
			(hide yes)
			(effects
				(font
					(size 1.27 1.016)
					(thickness 0.1524)
				)
				(justify mirror)
			)
		)
		(duplicate_pad_numbers_are_jumpers no)
		(fp_line
			(start 5.588 -3.2258)
			(end -4.7498 -3.2258)
			(stroke
				(width 0.1524)
				(type default)
			)
			(layer "B.SilkS")
		)
		(fp_line
			(start -4.7498 -3.2258)
			(end -4.7498 3.2258)
			(stroke
				(width 0.1524)
				(type default)
			)
			(layer "B.SilkS")
		)
		(fp_line
			(start 5.588 -0.50038)
			(end 5.08762 0)
			(stroke
				(width 0.1524)
				(type default)
			)
			(layer "B.SilkS")
		)
		(fp_line
			(start 5.08762 0)
			(end 5.588 0.50038)
			(stroke
				(width 0.1524)
				(type default)
			)
			(layer "B.SilkS")
		)
		(fp_line
			(start 5.588 3.2258)
			(end 5.588 -3.2258)
			(stroke
				(width 0.1524)
				(type default)
			)
			(layer "B.SilkS")
		)
		(fp_line
			(start 5.4102 3.2258)
			(end 5.4102 5.7912)
			(stroke
				(width 0.508)
				(type default)
			)
			(layer "B.SilkS")
		)
		(fp_line
			(start -4.7498 3.2258)
			(end 5.588 3.2258)
			(stroke
				(width 0.1524)
				(type default)
			)
			(layer "B.SilkS")
		)
		(fp_poly
			(pts
				(xy 4.764786 -3.2258) (xy -4.7625 -3.2258) (xy -4.7625 3.2258) (xy 4.764786 3.2258)
			)
			(stroke
				(width 0)
				(type default)
			)
			(fill yes)
			(layer "B.SilkS")
		)
		(fp_rect
			(start 5.1435 5.1562)
			(end -5.1435 -5.1562)
			(stroke
				(width 0)
				(type default)
			)
			(fill no)
			(layer "B.CrtYd")
		)
		(fp_poly
			(pts
				(xy 5.6642 6.0452) (xy 5.6642 -6.0452) (xy -5.6642 -6.0452) (xy -5.6642 -1.7653) (xy -5.1435 -1.7653)
				(xy -5.1435 -5.1562) (xy 5.1435 -5.1562) (xy 5.1435 5.1562) (xy -5.1435 5.1562) (xy -5.1435 -1.7526)
				(xy -5.6642 -1.7526) (xy -5.6642 6.0452)
			)
			(stroke
				(width 0)
				(type default)
			)
			(fill no)
			(layer "B.CrtYd")
		)
		(fp_rect
			(start 5.6642 6.0452)
			(end -5.6642 -6.0452)
			(stroke
				(width 0)
				(type default)
			)
			(fill no)
			(layer "B.Fab")
		)
		(pad "1" smd rect
			(at 4.445 4.71805 270)
			(size 0.635 1.651)
			(layers "B.Cu" "B.Mask" "B.Paste")
			(net "PU_BIOS_SPI_HOLD1_N")
		)
		(pad "2" smd rect
			(at 3.175 4.71805 270)
			(size 0.635 1.651)
			(layers "B.Cu" "B.Mask" "B.Paste")
			(net "P3V3_STBY")
		)
		(pad "3" smd rect
			(at 1.905 4.71805 270)
			(size 0.635 1.651)
			(layers "B.Cu" "B.Mask" "B.Paste")
			(net "PU_SPI1_RST")
		)
		(pad "4" smd rect
			(at 0.635 4.71805 270)
			(size 0.635 1.651)
			(layers "B.Cu" "B.Mask" "B.Paste")
			(net "TP_SPI_1_6")
		)
		(pad "5" smd rect
			(at -0.635 4.71805 270)
			(size 0.635 1.651)
			(layers "B.Cu" "B.Mask" "B.Paste")
			(net "TP_SPI_1_5")
		)
		(pad "6" smd rect
			(at -1.905 4.71805 270)
			(size 0.635 1.651)
			(layers "B.Cu" "B.Mask" "B.Paste")
			(net "TP_SPI_1_4")
		)
		(pad "7" smd rect
			(at -3.175 4.71805 270)
			(size 0.635 1.651)
			(layers "B.Cu" "B.Mask" "B.Paste")
			(net "SPI_CS0_SECONDARY_R_N")
		)
		(pad "8" smd rect
			(at -4.445 4.71805 270)
			(size 0.635 1.651)
			(layers "B.Cu" "B.Mask" "B.Paste")
			(net "SPI_MISO_R1")
		)
		(pad "9" smd rect
			(at -4.445 -4.71805 270)
			(size 0.635 1.651)
			(layers "B.Cu" "B.Mask" "B.Paste")
			(net "PU_BIOS_SPI_WP1_N")
		)
		(pad "10" smd rect
			(at -3.175 -4.71805 270)
			(size 0.635 1.651)
			(layers "B.Cu" "B.Mask" "B.Paste")
			(net "GND")
		)
		(pad "11" smd rect
			(at -1.905 -4.71805 270)
			(size 0.635 1.651)
			(layers "B.Cu" "B.Mask" "B.Paste")
			(net "TP_SPI_1_3")
		)
		(pad "12" smd rect
			(at -0.635 -4.71805 270)
			(size 0.635 1.651)
			(layers "B.Cu" "B.Mask" "B.Paste")
			(net "TP_SPI_1_2")
		)
		(pad "13" smd rect
			(at 0.635 -4.71805 270)
			(size 0.635 1.651)
			(layers "B.Cu" "B.Mask" "B.Paste")
			(net "TP_SPI_1_1")
		)
		(pad "14" smd rect
			(at 1.905 -4.71805 270)
			(size 0.635 1.651)
			(layers "B.Cu" "B.Mask" "B.Paste")
			(net "TP_SPI_1_0")
		)
		(pad "15" smd rect
			(at 3.175 -4.71805 270)
			(size 0.635 1.651)
			(layers "B.Cu" "B.Mask" "B.Paste")
			(net "SPI_SWITCH_MOSI_R1")
		)
		(pad "16" smd rect
			(at 4.445 -4.71805 270)
			(size 0.635 1.651)
			(layers "B.Cu" "B.Mask" "B.Paste")
			(net "SPI_CLK_R1")
		)
	)
	(footprint ""
		(layer "B.Cu")
		(at 351.663 -133.223 180)
		(property "Reference" "C3M16"
			(at 0 0 0)
			(layer "B.SilkS")
			(hide yes)
			(effects
				(font
					(size 1.27 1.27)
				)
				(justify mirror)
			)
		)
		(property "Value" ""
			(at 0 0 0)
			(layer "B.Fab")
			(effects
				(font
					(size 1.27 1.27)
				)
				(justify mirror)
			)
		)
		(duplicate_pad_numbers_are_jumpers no)
		(fp_poly
			(pts
				(xy 0.7239 -0.2159) (xy -0.7239 -0.2159) (xy -0.7239 1.9939) (xy 0.7239 1.9939)
			)
			(stroke
				(width 0)
				(type default)
			)
			(fill no)
			(layer "B.CrtYd")
		)
		(fp_line
			(start 0.7239 1.9939)
			(end -0.7239 1.9939)
			(stroke
				(width 0.1)
				(type default)
			)
			(layer "B.Fab")
		)
		(fp_line
			(start 0.7239 -0.2159)
			(end 0.7239 1.9939)
			(stroke
				(width 0.1)
				(type default)
			)
			(layer "B.Fab")
		)
		(fp_line
			(start -0.7239 1.9939)
			(end -0.7239 -0.2159)
			(stroke
				(width 0.1)
				(type default)
			)
			(layer "B.Fab")
		)
		(fp_line
			(start -0.7239 -0.2159)
			(end 0.7239 -0.2159)
			(stroke
				(width 0.1)
				(type default)
			)
			(layer "B.Fab")
		)
		(pad "1" smd rect
			(at 0 0)
			(size 1.27 1.016)
			(layers "B.Cu" "B.Mask" "B.Paste")
			(net "VR_FET_SW_P12V_STBY_PVPP_DEF")
		)
		(pad "2" smd rect
			(at 0 1.778)
			(size 1.27 1.016)
			(layers "B.Cu" "B.Mask" "B.Paste")
			(net "GND")
		)
		(zone
			(layer "B.Cu")
			(hatch none 0.5)
			(connect_pads
				(clearance 0)
			)
			(min_thickness 0.25)
			(keepout
				(tracks not_allowed)
				(vias allowed)
				(pads allowed)
				(copperpour not_allowed)
				(footprints allowed)
			)
			(placement
				(enabled no)
				(sheetname "")
			)
			(fill
				(thermal_gap 0.5)
				(thermal_bridge_width 0.5)
				(island_removal_mode 0)
			)
			(polygon
				(pts
					(xy 351.028 -133.731) (xy 352.298 -133.731) (xy 352.298 -134.493) (xy 351.028 -134.493)
				)
			)
		)
	)
	(footprint ""
		(layer "B.Cu")
		(at 352.904806 -60.368434)
		(property "Reference" "R2U28"
			(at 0 0 0)
			(layer "B.SilkS")
			(hide yes)
			(effects
				(font
					(size 1.27 1.27)
				)
				(justify mirror)
			)
		)
		(property "Value" ""
			(at 0 0 0)
			(layer "B.Fab")
			(effects
				(font
					(size 1.27 1.27)
				)
				(justify mirror)
			)
		)
		(duplicate_pad_numbers_are_jumpers no)
		(fp_poly
			(pts
				(xy 0.2794 -0.1016) (xy -0.2794 -0.1016) (xy -0.2794 0.9906) (xy 0.2794 0.9906)
			)
			(stroke
				(width 0)
				(type default)
			)
			(fill no)
			(layer "B.CrtYd")
		)
		(fp_line
			(start -0.2794 -0.1016)
			(end 0.2794 -0.1016)
			(stroke
				(width 0.1)
				(type default)
			)
			(layer "B.Fab")
		)
		(fp_line
			(start -0.2794 0.9906)
			(end -0.2794 -0.1016)
			(stroke
				(width 0.1)
				(type default)
			)
			(layer "B.Fab")
		)
		(fp_line
			(start 0.2794 -0.1016)
			(end 0.2794 0.9906)
			(stroke
				(width 0.1)
				(type default)
			)
			(layer "B.Fab")
		)
		(fp_line
			(start 0.2794 0.9906)
			(end -0.2794 0.9906)
			(stroke
				(width 0.1)
				(type default)
			)
			(layer "B.Fab")
		)
		(pad "1" smd rect
			(at 0 0 180)
			(size 0.508 0.508)
			(layers "B.Cu" "B.Mask" "B.Paste")
			(net "P3E_CPU0_PE1_SS_RXP<7>")
		)
		(pad "2" smd rect
			(at 0 0.889 180)
			(size 0.508 0.508)
			(layers "B.Cu" "B.Mask" "B.Paste")
			(net "P3E_CPU0_PE1_SS_R_RXP<7>")
		)
		(zone
			(layer "B.Cu")
			(hatch none 0.5)
			(connect_pads
				(clearance 0)
			)
			(min_thickness 0.25)
			(keepout
				(tracks allowed)
				(vias not_allowed)
				(pads allowed)
				(copperpour not_allowed)
				(footprints allowed)
			)
			(placement
				(enabled no)
				(sheetname "")
			)
			(fill
				(thermal_gap 0.5)
				(thermal_bridge_width 0.5)
				(island_removal_mode 0)
			)
			(polygon
				(pts
					(xy 353.158806 -60.114434) (xy 352.650806 -60.114434) (xy 352.650806 -59.733434) (xy 353.158806 -59.733434)
				)
			)
		)
		(zone
			(layer "B.Cu")
			(hatch none 0.5)
			(connect_pads
				(clearance 0)
			)
			(min_thickness 0.25)
			(keepout
				(tracks not_allowed)
				(vias allowed)
				(pads allowed)
				(copperpour not_allowed)
				(footprints allowed)
			)
			(placement
				(enabled no)
				(sheetname "")
			)
			(fill
				(thermal_gap 0.5)
				(thermal_bridge_width 0.5)
				(island_removal_mode 0)
			)
			(polygon
				(pts
					(xy 353.158806 -59.733434) (xy 352.650806 -59.733434) (xy 352.650806 -60.114434) (xy 353.158806 -60.114434)
				)
			)
		)
	)
	(footprint ""
		(layer "B.Cu")
		(at 210.612228 -100.676202 -90)
		(property "Reference" "C6N1"
			(at -1.659128 -3.382772 0)
			(unlocked yes)
			(layer "B.SilkS")
			(effects
				(font
					(size 0.7874 0.5842)
					(thickness 0.1524)
				)
				(justify mirror)
			)
		)
		(property "Value" ""
			(at 0 0 90)
			(layer "B.Fab")
			(effects
				(font
					(size 1.27 1.27)
				)
				(justify mirror)
			)
		)
		(duplicate_pad_numbers_are_jumpers no)
		(fp_line
			(start -2.286 7.366)
			(end -1.600708 7.366)
			(stroke
				(width 0.1524)
				(type default)
			)
			(layer "B.SilkS")
		)
		(fp_line
			(start -2.286 7.366)
			(end -2.286 1.63195)
			(stroke
				(width 0.1524)
				(type default)
			)
			(layer "B.SilkS")
		)
		(fp_line
			(start 2.286 7.366)
			(end 1.60147 7.366)
			(stroke
				(width 0.1524)
				(type default)
			)
			(layer "B.SilkS")
		)
		(fp_line
			(start 2.286 7.366)
			(end 2.286 1.632712)
			(stroke
				(width 0.1524)
				(type default)
			)
			(layer "B.SilkS")
		)
		(fp_line
			(start -2.504948 1.633728)
			(end -1.6002 1.633728)
			(stroke
				(width 0.1524)
				(type default)
			)
			(layer "B.SilkS")
		)
		(fp_line
			(start 2.563114 1.633728)
			(end 1.6002 1.633728)
			(stroke
				(width 0.1524)
				(type default)
			)
			(layer "B.SilkS")
		)
		(fp_line
			(start -2.504948 -1.616456)
			(end -2.504948 1.633728)
			(stroke
				(width 0.1524)
				(type default)
			)
			(layer "B.SilkS")
		)
		(fp_line
			(start -1.6002 -1.616456)
			(end -2.504948 -1.616456)
			(stroke
				(width 0.1524)
				(type default)
			)
			(layer "B.SilkS")
		)
		(fp_line
			(start 1.6002 -1.616456)
			(end 2.563114 -1.616456)
			(stroke
				(width 0.1524)
				(type default)
			)
			(layer "B.SilkS")
		)
		(fp_line
			(start 2.563114 -1.616456)
			(end 2.563114 1.633728)
			(stroke
				(width 0.1524)
				(type default)
			)
			(layer "B.SilkS")
		)
		(fp_rect
			(start 2.286 7.366)
			(end -2.286 -0.254)
			(stroke
				(width 0)
				(type default)
			)
			(fill no)
			(layer "B.CrtYd")
		)
		(fp_line
			(start -2.286 7.366)
			(end 2.286 7.366)
			(stroke
				(width 0.1)
				(type default)
			)
			(layer "B.Fab")
		)
		(fp_line
			(start 2.286 7.366)
			(end 2.286 -0.254)
			(stroke
				(width 0.1)
				(type default)
			)
			(layer "B.Fab")
		)
		(fp_line
			(start -2.286 -0.254)
			(end -2.286 7.366)
			(stroke
				(width 0.1)
				(type default)
			)
			(layer "B.Fab")
		)
		(fp_line
			(start 2.286 -0.254)
			(end -2.286 -0.254)
			(stroke
				(width 0.1)
				(type default)
			)
			(layer "B.Fab")
		)
		(pad "1" smd rect
			(at 0 0 90)
			(size 2.54 3.048)
			(layers "B.Cu" "B.Mask" "B.Paste")
			(net "PVSA_CPU0")
		)
		(pad "2" smd rect
			(at 0 7.112 90)
			(size 2.54 3.048)
			(layers "B.Cu" "B.Mask" "B.Paste")
			(net "GND")
		)
	)
	(footprint ""
		(layer "B.Cu")
		(at 271.604486 -68.17614 180)
		(property "Reference" "C5P42"
			(at 0 0 0)
			(layer "B.SilkS")
			(hide yes)
			(effects
				(font
					(size 1.27 1.27)
				)
				(justify mirror)
			)
		)
		(property "Value" ""
			(at 0 0 0)
			(layer "B.Fab")
			(effects
				(font
					(size 1.27 1.27)
				)
				(justify mirror)
			)
		)
		(duplicate_pad_numbers_are_jumpers no)
		(fp_poly
			(pts
				(xy 0.7239 -0.2159) (xy -0.7239 -0.2159) (xy -0.7239 1.9939) (xy 0.7239 1.9939)
			)
			(stroke
				(width 0)
				(type default)
			)
			(fill no)
			(layer "B.CrtYd")
		)
		(fp_line
			(start 0.7239 1.9939)
			(end -0.7239 1.9939)
			(stroke
				(width 0.1)
				(type default)
			)
			(layer "B.Fab")
		)
		(fp_line
			(start 0.7239 -0.2159)
			(end 0.7239 1.9939)
			(stroke
				(width 0.1)
				(type default)
			)
			(layer "B.Fab")
		)
		(fp_line
			(start -0.7239 1.9939)
			(end -0.7239 -0.2159)
			(stroke
				(width 0.1)
				(type default)
			)
			(layer "B.Fab")
		)
		(fp_line
			(start -0.7239 -0.2159)
			(end 0.7239 -0.2159)
			(stroke
				(width 0.1)
				(type default)
			)
			(layer "B.Fab")
		)
		(pad "1" smd rect
			(at 0 0)
			(size 1.27 1.016)
			(layers "B.Cu" "B.Mask" "B.Paste")
			(net "PVDDQ_ABC")
		)
		(pad "2" smd rect
			(at 0 1.778)
			(size 1.27 1.016)
			(layers "B.Cu" "B.Mask" "B.Paste")
			(net "GND")
		)
		(zone
			(layer "B.Cu")
			(hatch none 0.5)
			(connect_pads
				(clearance 0)
			)
			(min_thickness 0.25)
			(keepout
				(tracks not_allowed)
				(vias allowed)
				(pads allowed)
				(copperpour not_allowed)
				(footprints allowed)
			)
			(placement
				(enabled no)
				(sheetname "")
			)
			(fill
				(thermal_gap 0.5)
				(thermal_bridge_width 0.5)
				(island_removal_mode 0)
			)
			(polygon
				(pts
					(xy 270.969486 -68.68414) (xy 272.239486 -68.68414) (xy 272.239486 -69.44614) (xy 270.969486 -69.44614)
				)
			)
		)
	)
	(footprint ""
		(layer "B.Cu")
		(at 348.794578 -99.966272 -90)
		(property "Reference" "R3N7"
			(at 0 0 90)
			(layer "B.SilkS")
			(hide yes)
			(effects
				(font
					(size 1.27 1.27)
				)
				(justify mirror)
			)
		)
		(property "Value" ""
			(at 0 0 90)
			(layer "B.Fab")
			(effects
				(font
					(size 1.27 1.27)
				)
				(justify mirror)
			)
		)
		(duplicate_pad_numbers_are_jumpers no)
		(fp_poly
			(pts
				(xy 0.2794 -0.1016) (xy -0.2794 -0.1016) (xy -0.2794 0.9906) (xy 0.2794 0.9906)
			)
			(stroke
				(width 0)
				(type default)
			)
			(fill no)
			(layer "B.CrtYd")
		)
		(fp_line
			(start -0.2794 0.9906)
			(end -0.2794 -0.1016)
			(stroke
				(width 0.1)
				(type default)
			)
			(layer "B.Fab")
		)
		(fp_line
			(start 0.2794 0.9906)
			(end -0.2794 0.9906)
			(stroke
				(width 0.1)
				(type default)
			)
			(layer "B.Fab")
		)
		(fp_line
			(start -0.2794 -0.1016)
			(end 0.2794 -0.1016)
			(stroke
				(width 0.1)
				(type default)
			)
			(layer "B.Fab")
		)
		(fp_line
			(start 0.2794 -0.1016)
			(end 0.2794 0.9906)
			(stroke
				(width 0.1)
				(type default)
			)
			(layer "B.Fab")
		)
		(pad "1" smd rect
			(at 0 0 90)
			(size 0.508 0.508)
			(layers "B.Cu" "B.Mask" "B.Paste")
			(net "VR_PVCCIO_CPU0_PH1_VCIN")
		)
		(pad "2" smd rect
			(at 0 0.889 90)
			(size 0.508 0.508)
			(layers "B.Cu" "B.Mask" "B.Paste")
			(net "P5V_STBY")
		)
		(zone
			(layer "B.Cu")
			(hatch none 0.5)
			(connect_pads
				(clearance 0)
			)
			(min_thickness 0.25)
			(keepout
				(tracks not_allowed)
				(vias allowed)
				(pads allowed)
				(copperpour not_allowed)
				(footprints allowed)
			)
			(placement
				(enabled no)
				(sheetname "")
			)
			(fill
				(thermal_gap 0.5)
				(thermal_bridge_width 0.5)
				(island_removal_mode 0)
			)
			(polygon
				(pts
					(xy 348.159578 -99.712272) (xy 348.159578 -100.220272) (xy 348.540578 -100.220272) (xy 348.540578 -99.712272)
				)
			)
		)
		(zone
			(layer "B.Cu")
			(hatch none 0.5)
			(connect_pads
				(clearance 0)
			)
			(min_thickness 0.25)
			(keepout
				(tracks allowed)
				(vias not_allowed)
				(pads allowed)
				(copperpour not_allowed)
				(footprints allowed)
			)
			(placement
				(enabled no)
				(sheetname "")
			)
			(fill
				(thermal_gap 0.5)
				(thermal_bridge_width 0.5)
				(island_removal_mode 0)
			)
			(polygon
				(pts
					(xy 348.540578 -99.712272) (xy 348.540578 -100.220272) (xy 348.159578 -100.220272) (xy 348.159578 -99.712272)
				)
			)
		)
	)
	(footprint ""
		(layer "B.Cu")
		(at 472.2368 -124.8791 90)
		(property "Reference" "R1M5"
			(at 0 0 90)
			(layer "B.SilkS")
			(hide yes)
			(effects
				(font
					(size 1.27 1.27)
				)
				(justify mirror)
			)
		)
		(property "Value" ""
			(at 0 0 90)
			(layer "B.Fab")
			(effects
				(font
					(size 1.27 1.27)
				)
				(justify mirror)
			)
		)
		(duplicate_pad_numbers_are_jumpers no)
		(fp_rect
			(start -0.2794 -0.1016)
			(end 0.2794 0.9906)
			(stroke
				(width 0)
				(type default)
			)
			(fill no)
			(layer "B.CrtYd")
		)
		(fp_line
			(start 0.2794 -0.1016)
			(end 0.2794 0.9906)
			(stroke
				(width 0.1)
				(type default)
			)
			(layer "B.Fab")
		)
		(fp_line
			(start -0.2794 -0.1016)
			(end 0.2794 -0.1016)
			(stroke
				(width 0.1)
				(type default)
			)
			(layer "B.Fab")
		)
		(fp_line
			(start 0.2794 0.9906)
			(end -0.2794 0.9906)
			(stroke
				(width 0.1)
				(type default)
			)
			(layer "B.Fab")
		)
		(fp_line
			(start -0.2794 0.9906)
			(end -0.2794 -0.1016)
			(stroke
				(width 0.1)
				(type default)
			)
			(layer "B.Fab")
		)
		(pad "1" smd rect
			(at 0 0 270)
			(size 0.508 0.508)
			(layers "B.Cu" "B.Mask" "B.Paste")
			(net "USB2_P01_DP")
		)
		(pad "2" smd rect
			(at 0 0.889 270)
			(size 0.508 0.508)
			(layers "B.Cu" "B.Mask" "B.Paste")
			(net "USB2_P01_ESD_DP")
		)
		(zone
			(layer "B.Cu")
			(hatch none 0.5)
			(connect_pads
				(clearance 0)
			)
			(min_thickness 0.25)
			(keepout
				(tracks allowed)
				(vias not_allowed)
				(pads allowed)
				(copperpour not_allowed)
				(footprints allowed)
			)
			(placement
				(enabled no)
				(sheetname "")
			)
			(fill
				(thermal_gap 0.5)
				(thermal_bridge_width 0.5)
				(island_removal_mode 0)
			)
			(polygon
				(pts
					(xy 472.4908 -124.6251) (xy 472.8718 -124.6251) (xy 472.8718 -125.1331) (xy 472.4908 -125.1331)
				)
			)
		)
	)
)
